(kicad_pcb
	(version 20260206)
	(generator "pcbnew")
	(generator_version "10.0")
	(general
		(thickness 1.6)
		(legacy_teardrops no)
	)
	(paper "A4")
	(title_block
		(title "12092022_DA0F0TMDCD0_F0T_Management_Board_D_brd_V3_OCP.brd")
		(comment 1 "Grand Teton / footprints 1129-1134 of 1440")
	)
	(layers
		(0 "F.Cu" signal "TOP")
		(4 "In1.Cu" signal "GND")
		(6 "In2.Cu" signal "IN1")
		(8 "In3.Cu" signal "GND1")
		(10 "In4.Cu" signal "IN2")
		(12 "In5.Cu" signal "VCC")
		(14 "In6.Cu" signal "VCC1")
		(16 "In7.Cu" signal "IN3")
		(18 "In8.Cu" signal "GND2")
		(20 "In9.Cu" signal "IN4")
		(22 "In10.Cu" signal "GND3")
		(2 "B.Cu" signal "BOTTOM")
		(9 "F.Adhes" user "F.Adhesive")
		(11 "B.Adhes" user "B.Adhesive")
		(13 "F.Paste" user "Package Geometry/Pastemask Top")
		(15 "B.Paste" user "Package Geometry/Pastemask Bottom")
		(5 "F.SilkS" user "Ref Des/Silkscreen Top")
		(7 "B.SilkS" user "Ref Des/Silkscreen Bottom")
		(1 "F.Mask" user "Board Geometry/Soldermask Top")
		(3 "B.Mask" user "Board Geometry/Soldermask Bottom")
		(17 "Dwgs.User" user "User.Drawings")
		(19 "Cmts.User" user "User.Comments")
		(21 "Eco1.User" user "User.Eco1")
		(23 "Eco2.User" user "User.Eco2")
		(25 "Edge.Cuts" user "Board Geometry/Outline")
		(27 "Margin" user)
		(31 "F.CrtYd" user "Package Geometry/Place Bound Top")
		(29 "B.CrtYd" user "Package Geometry/Place Bound Bottom")
		(35 "F.Fab" user "Ref Des/Assembly Top")
		(33 "B.Fab" user "Ref Des/Assembly Bottom")
	)
	(footprint ""
		(layer "B.Cu")
		(at 60.537598 -50.711862 90)
		(property "Reference" "C74"
			(at 0 0 90)
			(layer "B.SilkS")
			(hide yes)
			(effects
				(font
					(size 1.27 1.27)
				)
				(justify mirror)
			)
		)
		(property "Value" ""
			(at 0 0 90)
			(layer "B.Fab")
			(effects
				(font
					(size 1.27 1.27)
				)
				(justify mirror)
			)
		)
		(duplicate_pad_numbers_are_jumpers no)
		(fp_line
			(start 0.7874 -0.4064)
			(end -0.7874 -0.4064)
			(stroke
				(width 0.1524)
				(type default)
			)
			(layer "B.SilkS")
		)
		(fp_line
			(start -0.7874 -0.4064)
			(end -0.7874 0.4064)
			(stroke
				(width 0.1524)
				(type default)
			)
			(layer "B.SilkS")
		)
		(fp_line
			(start 0.7874 0.4064)
			(end 0.7874 -0.4064)
			(stroke
				(width 0.1524)
				(type default)
			)
			(layer "B.SilkS")
		)
		(fp_line
			(start -0.7874 0.4064)
			(end 0.7874 0.4064)
			(stroke
				(width 0.1524)
				(type default)
			)
			(layer "B.SilkS")
		)
		(fp_line
			(start 0.67945 -0.305054)
			(end 0.12065 -0.305054)
			(stroke
				(width 0.1)
				(type default)
			)
			(layer "B.Fab")
		)
		(fp_line
			(start 0.12065 -0.305054)
			(end 0.12065 -0.2794)
			(stroke
				(width 0.1)
				(type default)
			)
			(layer "B.Fab")
		)
		(fp_line
			(start -0.12065 -0.3048)
			(end -0.67945 -0.3048)
			(stroke
				(width 0.1)
				(type default)
			)
			(layer "B.Fab")
		)
		(fp_line
			(start -0.67945 -0.3048)
			(end -0.67945 0.3048)
			(stroke
				(width 0.1)
				(type default)
			)
			(layer "B.Fab")
		)
		(fp_line
			(start 0.12065 -0.2794)
			(end -0.12065 -0.2794)
			(stroke
				(width 0.1)
				(type default)
			)
			(layer "B.Fab")
		)
		(fp_line
			(start -0.12065 -0.2794)
			(end -0.12065 -0.3048)
			(stroke
				(width 0.1)
				(type default)
			)
			(layer "B.Fab")
		)
		(fp_line
			(start 0.12065 0.2794)
			(end 0.12065 0.3048)
			(stroke
				(width 0.1)
				(type default)
			)
			(layer "B.Fab")
		)
		(fp_line
			(start -0.120396 0.2794)
			(end 0.12065 0.2794)
			(stroke
				(width 0.1)
				(type default)
			)
			(layer "B.Fab")
		)
		(fp_line
			(start 0.67945 0.3048)
			(end 0.67945 -0.305054)
			(stroke
				(width 0.1)
				(type default)
			)
			(layer "B.Fab")
		)
		(fp_line
			(start 0.12065 0.3048)
			(end 0.67945 0.3048)
			(stroke
				(width 0.1)
				(type default)
			)
			(layer "B.Fab")
		)
		(fp_line
			(start -0.120396 0.3048)
			(end -0.120396 0.2794)
			(stroke
				(width 0.1)
				(type default)
			)
			(layer "B.Fab")
		)
		(fp_line
			(start -0.67945 0.3048)
			(end -0.120396 0.3048)
			(stroke
				(width 0.1)
				(type default)
			)
			(layer "B.Fab")
		)
		(pad "1" smd circle
			(at 0.40005 0 270)
			(size 0 0)
			(layers "B.Cu" "B.Mask" "B.Paste")
			(net "P1V2_AUX")
		)
		(pad "2" smd circle
			(at -0.40005 0 270)
			(size 0 0)
			(layers "B.Cu" "B.Mask" "B.Paste")
			(net "GND")
		)
	)
	(footprint ""
		(layer "B.Cu")
		(at 4.6482 -29.5148)
		(property "Reference" "R765"
			(at 0 0 0)
			(layer "B.SilkS")
			(hide yes)
			(effects
				(font
					(size 1.27 1.27)
				)
				(justify mirror)
			)
		)
		(property "Value" ""
			(at 0 0 0)
			(layer "B.Fab")
			(effects
				(font
					(size 1.27 1.27)
				)
				(justify mirror)
			)
		)
		(duplicate_pad_numbers_are_jumpers no)
		(fp_line
			(start -0.7874 -0.4064)
			(end -0.7874 0.4064)
			(stroke
				(width 0.1524)
				(type default)
			)
			(layer "B.SilkS")
		)
		(fp_line
			(start -0.7874 0.4064)
			(end 0.7874 0.4064)
			(stroke
				(width 0.1524)
				(type default)
			)
			(layer "B.SilkS")
		)
		(fp_line
			(start 0.7874 -0.4064)
			(end -0.7874 -0.4064)
			(stroke
				(width 0.1524)
				(type default)
			)
			(layer "B.SilkS")
		)
		(fp_line
			(start 0.7874 0.4064)
			(end 0.7874 -0.4064)
			(stroke
				(width 0.1524)
				(type default)
			)
			(layer "B.SilkS")
		)
		(fp_line
			(start -0.67945 -0.3048)
			(end -0.67945 0.3048)
			(stroke
				(width 0.1)
				(type default)
			)
			(layer "B.Fab")
		)
		(fp_line
			(start -0.67945 0.3048)
			(end -0.120396 0.3048)
			(stroke
				(width 0.1)
				(type default)
			)
			(layer "B.Fab")
		)
		(fp_line
			(start -0.12065 -0.3048)
			(end -0.67945 -0.3048)
			(stroke
				(width 0.1)
				(type default)
			)
			(layer "B.Fab")
		)
		(fp_line
			(start -0.12065 -0.2794)
			(end -0.12065 -0.3048)
			(stroke
				(width 0.1)
				(type default)
			)
			(layer "B.Fab")
		)
		(fp_line
			(start -0.120396 0.2794)
			(end 0.12065 0.2794)
			(stroke
				(width 0.1)
				(type default)
			)
			(layer "B.Fab")
		)
		(fp_line
			(start -0.120396 0.3048)
			(end -0.120396 0.2794)
			(stroke
				(width 0.1)
				(type default)
			)
			(layer "B.Fab")
		)
		(fp_line
			(start 0.12065 -0.305054)
			(end 0.12065 -0.2794)
			(stroke
				(width 0.1)
				(type default)
			)
			(layer "B.Fab")
		)
		(fp_line
			(start 0.12065 -0.2794)
			(end -0.12065 -0.2794)
			(stroke
				(width 0.1)
				(type default)
			)
			(layer "B.Fab")
		)
		(fp_line
			(start 0.12065 0.2794)
			(end 0.12065 0.3048)
			(stroke
				(width 0.1)
				(type default)
			)
			(layer "B.Fab")
		)
		(fp_line
			(start 0.12065 0.3048)
			(end 0.67945 0.3048)
			(stroke
				(width 0.1)
				(type default)
			)
			(layer "B.Fab")
		)
		(fp_line
			(start 0.67945 -0.305054)
			(end 0.12065 -0.305054)
			(stroke
				(width 0.1)
				(type default)
			)
			(layer "B.Fab")
		)
		(fp_line
			(start 0.67945 0.3048)
			(end 0.67945 -0.305054)
			(stroke
				(width 0.1)
				(type default)
			)
			(layer "B.Fab")
		)
		(pad "1" smd circle
			(at 0.40005 0 180)
			(size 0 0)
			(layers "B.Cu" "B.Mask" "B.Paste")
			(net "P3V3_AUX")
		)
		(pad "2" smd circle
			(at -0.40005 0 180)
			(size 0 0)
			(layers "B.Cu" "B.Mask" "B.Paste")
			(net "UART_BMC_5_TXD_BUF_R")
		)
	)
	(footprint ""
		(layer "B.Cu")
		(at 43.434 -67.818)
		(property "Reference" "R640"
			(at 0 0 0)
			(layer "B.SilkS")
			(hide yes)
			(effects
				(font
					(size 1.27 1.27)
				)
				(justify mirror)
			)
		)
		(property "Value" ""
			(at 0 0 0)
			(layer "B.Fab")
			(effects
				(font
					(size 1.27 1.27)
				)
				(justify mirror)
			)
		)
		(duplicate_pad_numbers_are_jumpers no)
		(fp_line
			(start -0.7874 -0.4064)
			(end -0.7874 0.4064)
			(stroke
				(width 0.1524)
				(type default)
			)
			(layer "B.SilkS")
		)
		(fp_line
			(start -0.7874 0.4064)
			(end 0.7874 0.4064)
			(stroke
				(width 0.1524)
				(type default)
			)
			(layer "B.SilkS")
		)
		(fp_line
			(start 0.7874 -0.4064)
			(end -0.7874 -0.4064)
			(stroke
				(width 0.1524)
				(type default)
			)
			(layer "B.SilkS")
		)
		(fp_line
			(start 0.7874 0.4064)
			(end 0.7874 -0.4064)
			(stroke
				(width 0.1524)
				(type default)
			)
			(layer "B.SilkS")
		)
		(fp_line
			(start -0.67945 -0.3048)
			(end -0.67945 0.3048)
			(stroke
				(width 0.1)
				(type default)
			)
			(layer "B.Fab")
		)
		(fp_line
			(start -0.67945 0.3048)
			(end -0.120396 0.3048)
			(stroke
				(width 0.1)
				(type default)
			)
			(layer "B.Fab")
		)
		(fp_line
			(start -0.12065 -0.3048)
			(end -0.67945 -0.3048)
			(stroke
				(width 0.1)
				(type default)
			)
			(layer "B.Fab")
		)
		(fp_line
			(start -0.12065 -0.2794)
			(end -0.12065 -0.3048)
			(stroke
				(width 0.1)
				(type default)
			)
			(layer "B.Fab")
		)
		(fp_line
			(start -0.120396 0.2794)
			(end 0.12065 0.2794)
			(stroke
				(width 0.1)
				(type default)
			)
			(layer "B.Fab")
		)
		(fp_line
			(start -0.120396 0.3048)
			(end -0.120396 0.2794)
			(stroke
				(width 0.1)
				(type default)
			)
			(layer "B.Fab")
		)
		(fp_line
			(start 0.12065 -0.305054)
			(end 0.12065 -0.2794)
			(stroke
				(width 0.1)
				(type default)
			)
			(layer "B.Fab")
		)
		(fp_line
			(start 0.12065 -0.2794)
			(end -0.12065 -0.2794)
			(stroke
				(width 0.1)
				(type default)
			)
			(layer "B.Fab")
		)
		(fp_line
			(start 0.12065 0.2794)
			(end 0.12065 0.3048)
			(stroke
				(width 0.1)
				(type default)
			)
			(layer "B.Fab")
		)
		(fp_line
			(start 0.12065 0.3048)
			(end 0.67945 0.3048)
			(stroke
				(width 0.1)
				(type default)
			)
			(layer "B.Fab")
		)
		(fp_line
			(start 0.67945 -0.305054)
			(end 0.12065 -0.305054)
			(stroke
				(width 0.1)
				(type default)
			)
			(layer "B.Fab")
		)
		(fp_line
			(start 0.67945 0.3048)
			(end 0.67945 -0.305054)
			(stroke
				(width 0.1)
				(type default)
			)
			(layer "B.Fab")
		)
		(pad "1" smd circle
			(at 0.40005 0 180)
			(size 0 0)
			(layers "B.Cu" "B.Mask" "B.Paste")
			(net "P3V3_AUX")
		)
		(pad "2" smd circle
			(at -0.40005 0 180)
			(size 0 0)
			(layers "B.Cu" "B.Mask" "B.Paste")
			(net "FM_JTAG_BMC_MUX_SEL")
		)
	)
	(footprint ""
		(layer "B.Cu")
		(at 14.7828 -95.5802 180)
		(property "Reference" "R835"
			(at 0 0 0)
			(layer "B.SilkS")
			(hide yes)
			(effects
				(font
					(size 1.27 1.27)
				)
				(justify mirror)
			)
		)
		(property "Value" ""
			(at 0 0 0)
			(layer "B.Fab")
			(effects
				(font
					(size 1.27 1.27)
				)
				(justify mirror)
			)
		)
		(duplicate_pad_numbers_are_jumpers no)
		(fp_line
			(start 0.7874 0.4064)
			(end 0.7874 -0.4064)
			(stroke
				(width 0.1524)
				(type default)
			)
			(layer "B.SilkS")
		)
		(fp_line
			(start 0.7874 -0.4064)
			(end -0.7874 -0.4064)
			(stroke
				(width 0.1524)
				(type default)
			)
			(layer "B.SilkS")
		)
		(fp_line
			(start -0.7874 0.4064)
			(end 0.7874 0.4064)
			(stroke
				(width 0.1524)
				(type default)
			)
			(layer "B.SilkS")
		)
		(fp_line
			(start -0.7874 -0.4064)
			(end -0.7874 0.4064)
			(stroke
				(width 0.1524)
				(type default)
			)
			(layer "B.SilkS")
		)
		(fp_line
			(start 0.67945 0.3048)
			(end 0.67945 -0.305054)
			(stroke
				(width 0.1)
				(type default)
			)
			(layer "B.Fab")
		)
		(fp_line
			(start 0.67945 -0.305054)
			(end 0.12065 -0.305054)
			(stroke
				(width 0.1)
				(type default)
			)
			(layer "B.Fab")
		)
		(fp_line
			(start 0.12065 0.3048)
			(end 0.67945 0.3048)
			(stroke
				(width 0.1)
				(type default)
			)
			(layer "B.Fab")
		)
		(fp_line
			(start 0.12065 0.2794)
			(end 0.12065 0.3048)
			(stroke
				(width 0.1)
				(type default)
			)
			(layer "B.Fab")
		)
		(fp_line
			(start 0.12065 -0.2794)
			(end -0.12065 -0.2794)
			(stroke
				(width 0.1)
				(type default)
			)
			(layer "B.Fab")
		)
		(fp_line
			(start 0.12065 -0.305054)
			(end 0.12065 -0.2794)
			(stroke
				(width 0.1)
				(type default)
			)
			(layer "B.Fab")
		)
		(fp_line
			(start -0.120396 0.3048)
			(end -0.120396 0.2794)
			(stroke
				(width 0.1)
				(type default)
			)
			(layer "B.Fab")
		)
		(fp_line
			(start -0.120396 0.2794)
			(end 0.12065 0.2794)
			(stroke
				(width 0.1)
				(type default)
			)
			(layer "B.Fab")
		)
		(fp_line
			(start -0.12065 -0.2794)
			(end -0.12065 -0.3048)
			(stroke
				(width 0.1)
				(type default)
			)
			(layer "B.Fab")
		)
		(fp_line
			(start -0.12065 -0.3048)
			(end -0.67945 -0.3048)
			(stroke
				(width 0.1)
				(type default)
			)
			(layer "B.Fab")
		)
		(fp_line
			(start -0.67945 0.3048)
			(end -0.120396 0.3048)
			(stroke
				(width 0.1)
				(type default)
			)
			(layer "B.Fab")
		)
		(fp_line
			(start -0.67945 -0.3048)
			(end -0.67945 0.3048)
			(stroke
				(width 0.1)
				(type default)
			)
			(layer "B.Fab")
		)
		(pad "1" smd circle
			(at 0.40005 0)
			(size 0 0)
			(layers "B.Cu" "B.Mask" "B.Paste")
			(net "P3V3_AUX")
		)
		(pad "2" smd circle
			(at -0.40005 0)
			(size 0 0)
			(layers "B.Cu" "B.Mask" "B.Paste")
			(net "FM_ADR_TRIGGER_N")
		)
	)
	(footprint ""
		(layer "B.Cu")
		(at 10.2616 -106.3752 -90)
		(property "Reference" "R811"
			(at 0 0 90)
			(layer "B.SilkS")
			(hide yes)
			(effects
				(font
					(size 1.27 1.27)
				)
				(justify mirror)
			)
		)
		(property "Value" ""
			(at 0 0 90)
			(layer "B.Fab")
			(effects
				(font
					(size 1.27 1.27)
				)
				(justify mirror)
			)
		)
		(duplicate_pad_numbers_are_jumpers no)
		(fp_line
			(start -0.7874 0.4064)
			(end 0.7874 0.4064)
			(stroke
				(width 0.1524)
				(type default)
			)
			(layer "B.SilkS")
		)
		(fp_line
			(start 0.7874 0.4064)
			(end 0.7874 -0.4064)
			(stroke
				(width 0.1524)
				(type default)
			)
			(layer "B.SilkS")
		)
		(fp_line
			(start -0.7874 -0.4064)
			(end -0.7874 0.4064)
			(stroke
				(width 0.1524)
				(type default)
			)
			(layer "B.SilkS")
		)
		(fp_line
			(start 0.7874 -0.4064)
			(end -0.7874 -0.4064)
			(stroke
				(width 0.1524)
				(type default)
			)
			(layer "B.SilkS")
		)
		(fp_line
			(start -0.67945 0.3048)
			(end -0.120396 0.3048)
			(stroke
				(width 0.1)
				(type default)
			)
			(layer "B.Fab")
		)
		(fp_line
			(start -0.120396 0.3048)
			(end -0.120396 0.2794)
			(stroke
				(width 0.1)
				(type default)
			)
			(layer "B.Fab")
		)
		(fp_line
			(start 0.12065 0.3048)
			(end 0.67945 0.3048)
			(stroke
				(width 0.1)
				(type default)
			)
			(layer "B.Fab")
		)
		(fp_line
			(start 0.67945 0.3048)
			(end 0.67945 -0.305054)
			(stroke
				(width 0.1)
				(type default)
			)
			(layer "B.Fab")
		)
		(fp_line
			(start -0.120396 0.2794)
			(end 0.12065 0.2794)
			(stroke
				(width 0.1)
				(type default)
			)
			(layer "B.Fab")
		)
		(fp_line
			(start 0.12065 0.2794)
			(end 0.12065 0.3048)
			(stroke
				(width 0.1)
				(type default)
			)
			(layer "B.Fab")
		)
		(fp_line
			(start -0.12065 -0.2794)
			(end -0.12065 -0.3048)
			(stroke
				(width 0.1)
				(type default)
			)
			(layer "B.Fab")
		)
		(fp_line
			(start 0.12065 -0.2794)
			(end -0.12065 -0.2794)
			(stroke
				(width 0.1)
				(type default)
			)
			(layer "B.Fab")
		)
		(fp_line
			(start -0.67945 -0.3048)
			(end -0.67945 0.3048)
			(stroke
				(width 0.1)
				(type default)
			)
			(layer "B.Fab")
		)
		(fp_line
			(start -0.12065 -0.3048)
			(end -0.67945 -0.3048)
			(stroke
				(width 0.1)
				(type default)
			)
			(layer "B.Fab")
		)
		(fp_line
			(start 0.12065 -0.305054)
			(end 0.12065 -0.2794)
			(stroke
				(width 0.1)
				(type default)
			)
			(layer "B.Fab")
		)
		(fp_line
			(start 0.67945 -0.305054)
			(end 0.12065 -0.305054)
			(stroke
				(width 0.1)
				(type default)
			)
			(layer "B.Fab")
		)
		(pad "1" smd circle
			(at 0.40005 0 90)
			(size 0 0)
			(layers "B.Cu" "B.Mask" "B.Paste")
			(net "PCH_BEEP_LED")
		)
		(pad "2" smd circle
			(at -0.40005 0 90)
			(size 0 0)
			(layers "B.Cu" "B.Mask" "B.Paste")
			(net "PCH_BEEP_R_LED")
		)
	)
	(footprint ""
		(layer "B.Cu")
		(at 78.74 -94.742)
		(property "Reference" "R716"
			(at 0 0 0)
			(layer "B.SilkS")
			(hide yes)
			(effects
				(font
					(size 1.27 1.27)
				)
				(justify mirror)
			)
		)
		(property "Value" ""
			(at 0 0 0)
			(layer "B.Fab")
			(effects
				(font
					(size 1.27 1.27)
				)
				(justify mirror)
			)
		)
		(duplicate_pad_numbers_are_jumpers no)
		(fp_line
			(start -0.7874 -0.4064)
			(end -0.7874 0.4064)
			(stroke
				(width 0.1524)
				(type default)
			)
			(layer "B.SilkS")
		)
		(fp_line
			(start -0.7874 0.4064)
			(end 0.7874 0.4064)
			(stroke
				(width 0.1524)
				(type default)
			)
			(layer "B.SilkS")
		)
		(fp_line
			(start 0.7874 -0.4064)
			(end -0.7874 -0.4064)
			(stroke
				(width 0.1524)
				(type default)
			)
			(layer "B.SilkS")
		)
		(fp_line
			(start 0.7874 0.4064)
			(end 0.7874 -0.4064)
			(stroke
				(width 0.1524)
				(type default)
			)
			(layer "B.SilkS")
		)
		(fp_line
			(start -0.67945 -0.3048)
			(end -0.67945 0.3048)
			(stroke
				(width 0.1)
				(type default)
			)
			(layer "B.Fab")
		)
		(fp_line
			(start -0.67945 0.3048)
			(end -0.120396 0.3048)
			(stroke
				(width 0.1)
				(type default)
			)
			(layer "B.Fab")
		)
		(fp_line
			(start -0.12065 -0.3048)
			(end -0.67945 -0.3048)
			(stroke
				(width 0.1)
				(type default)
			)
			(layer "B.Fab")
		)
		(fp_line
			(start -0.12065 -0.2794)
			(end -0.12065 -0.3048)
			(stroke
				(width 0.1)
				(type default)
			)
			(layer "B.Fab")
		)
		(fp_line
			(start -0.120396 0.2794)
			(end 0.12065 0.2794)
			(stroke
				(width 0.1)
				(type default)
			)
			(layer "B.Fab")
		)
		(fp_line
			(start -0.120396 0.3048)
			(end -0.120396 0.2794)
			(stroke
				(width 0.1)
				(type default)
			)
			(layer "B.Fab")
		)
		(fp_line
			(start 0.12065 -0.305054)
			(end 0.12065 -0.2794)
			(stroke
				(width 0.1)
				(type default)
			)
			(layer "B.Fab")
		)
		(fp_line
			(start 0.12065 -0.2794)
			(end -0.12065 -0.2794)
			(stroke
				(width 0.1)
				(type default)
			)
			(layer "B.Fab")
		)
		(fp_line
			(start 0.12065 0.2794)
			(end 0.12065 0.3048)
			(stroke
				(width 0.1)
				(type default)
			)
			(layer "B.Fab")
		)
		(fp_line
			(start 0.12065 0.3048)
			(end 0.67945 0.3048)
			(stroke
				(width 0.1)
				(type default)
			)
			(layer "B.Fab")
		)
		(fp_line
			(start 0.67945 -0.305054)
			(end 0.12065 -0.305054)
			(stroke
				(width 0.1)
				(type default)
			)
			(layer "B.Fab")
		)
		(fp_line
			(start 0.67945 0.3048)
			(end 0.67945 -0.305054)
			(stroke
				(width 0.1)
				(type default)
			)
			(layer "B.Fab")
		)
		(pad "1" smd circle
			(at 0.40005 0 180)
			(size 0 0)
			(layers "B.Cu" "B.Mask" "B.Paste")
			(net "P5V_AUX")
		)
		(pad "2" smd circle
			(at -0.40005 0 180)
			(size 0 0)
			(layers "B.Cu" "B.Mask" "B.Paste")
			(net "LPC_ESPI_SEL_N")
		)
	)
)
